(kicad_pcb
	(version 20260206)
	(generator "pcbnew")
	(generator_version "10.0")
	(general
		(thickness 1.6)
		(legacy_teardrops no)
	)
	(paper "A4")
	(title_block
		(title "04192023_DAF0TMB3IC0_F0TG_MB_C_brd_V02_OCP.brd")
		(comment 1 "Grand Teton / footprints 4893-4897 of 8354")
	)
	(layers
		(0 "F.Cu" signal "TOP")
		(4 "In1.Cu" signal "GND")
		(6 "In2.Cu" signal "IN1")
		(8 "In3.Cu" signal "GND1")
		(10 "In4.Cu" signal "IN2")
		(12 "In5.Cu" signal "GND2")
		(14 "In6.Cu" signal "IN3")
		(16 "In7.Cu" signal "GND3")
		(18 "In8.Cu" signal "VCC")
		(20 "In9.Cu" signal "VCC1")
		(22 "In10.Cu" signal "GND4")
		(24 "In11.Cu" signal "IN4")
		(26 "In12.Cu" signal "GND5")
		(28 "In13.Cu" signal "IN5")
		(30 "In14.Cu" signal "GND6")
		(32 "In15.Cu" signal "IN6")
		(34 "In16.Cu" signal "GND7")
		(2 "B.Cu" signal "BOTTOM")
		(9 "F.Adhes" user "F.Adhesive")
		(11 "B.Adhes" user "B.Adhesive")
		(13 "F.Paste" user "Package Geometry/Pastemask Top")
		(15 "B.Paste" user "Package Geometry/Pastemask Bottom")
		(5 "F.SilkS" user "Ref Des/Silkscreen Top")
		(7 "B.SilkS" user "Ref Des/Silkscreen Bottom")
		(1 "F.Mask" user "Board Geometry/Soldermask Top")
		(3 "B.Mask" user "Board Geometry/Soldermask Bottom")
		(17 "Dwgs.User" user "User.Drawings")
		(19 "Cmts.User" user "User.Comments")
		(21 "Eco1.User" user "User.Eco1")
		(23 "Eco2.User" user "User.Eco2")
		(25 "Edge.Cuts" user "Board Geometry/Outline")
		(27 "Margin" user)
		(31 "F.CrtYd" user "Package Geometry/Place Bound Top")
		(29 "B.CrtYd" user "Package Geometry/Place Bound Bottom")
		(35 "F.Fab" user "Ref Des/Assembly Top")
		(33 "B.Fab" user "Ref Des/Assembly Bottom")
	)
	(footprint ""
		(layer "F.Cu")
		(at 303.374298 -14.48181)
		(property "Reference" "R4197"
			(at 0 0 0)
			(layer "F.SilkS")
			(hide yes)
			(effects
				(font
					(size 1.27 1.27)
				)
			)
		)
		(property "Value" ""
			(at 0 0 0)
			(layer "F.Fab")
			(effects
				(font
					(size 1.27 1.27)
				)
			)
		)
		(duplicate_pad_numbers_are_jumpers no)
		(fp_line
			(start -0.7874 -0.4064)
			(end 0.7874 -0.4064)
			(stroke
				(width 0.1524)
				(type default)
			)
			(layer "F.SilkS")
		)
		(fp_line
			(start -0.7874 0.4064)
			(end -0.7874 -0.4064)
			(stroke
				(width 0.1524)
				(type default)
			)
			(layer "F.SilkS")
		)
		(fp_line
			(start 0.7874 -0.4064)
			(end 0.7874 0.4064)
			(stroke
				(width 0.1524)
				(type default)
			)
			(layer "F.SilkS")
		)
		(fp_line
			(start 0.7874 0.4064)
			(end -0.7874 0.4064)
			(stroke
				(width 0.1524)
				(type default)
			)
			(layer "F.SilkS")
		)
		(fp_line
			(start -0.67945 -0.305054)
			(end -0.12065 -0.305054)
			(stroke
				(width 0.1)
				(type default)
			)
			(layer "F.Fab")
		)
		(fp_line
			(start -0.67945 0.3048)
			(end -0.67945 -0.305054)
			(stroke
				(width 0.1)
				(type default)
			)
			(layer "F.Fab")
		)
		(fp_line
			(start -0.12065 -0.305054)
			(end -0.12065 -0.2794)
			(stroke
				(width 0.1)
				(type default)
			)
			(layer "F.Fab")
		)
		(fp_line
			(start -0.12065 -0.2794)
			(end 0.12065 -0.2794)
			(stroke
				(width 0.1)
				(type default)
			)
			(layer "F.Fab")
		)
		(fp_line
			(start -0.12065 0.2794)
			(end -0.12065 0.3048)
			(stroke
				(width 0.1)
				(type default)
			)
			(layer "F.Fab")
		)
		(fp_line
			(start -0.12065 0.3048)
			(end -0.67945 0.3048)
			(stroke
				(width 0.1)
				(type default)
			)
			(layer "F.Fab")
		)
		(fp_line
			(start 0.120396 0.2794)
			(end -0.12065 0.2794)
			(stroke
				(width 0.1)
				(type default)
			)
			(layer "F.Fab")
		)
		(fp_line
			(start 0.120396 0.3048)
			(end 0.120396 0.2794)
			(stroke
				(width 0.1)
				(type default)
			)
			(layer "F.Fab")
		)
		(fp_line
			(start 0.12065 -0.3048)
			(end 0.67945 -0.3048)
			(stroke
				(width 0.1)
				(type default)
			)
			(layer "F.Fab")
		)
		(fp_line
			(start 0.12065 -0.2794)
			(end 0.12065 -0.3048)
			(stroke
				(width 0.1)
				(type default)
			)
			(layer "F.Fab")
		)
		(fp_line
			(start 0.67945 -0.3048)
			(end 0.67945 0.3048)
			(stroke
				(width 0.1)
				(type default)
			)
			(layer "F.Fab")
		)
		(fp_line
			(start 0.67945 0.3048)
			(end 0.120396 0.3048)
			(stroke
				(width 0.1)
				(type default)
			)
			(layer "F.Fab")
		)
		(pad "1" smd circle
			(at -0.40005 0)
			(size 0 0)
			(layers "F.Cu" "F.Mask" "F.Paste")
			(net "U271_1_ADD1")
		)
		(pad "2" smd circle
			(at 0.40005 0)
			(size 0 0)
			(layers "F.Cu" "F.Mask" "F.Paste")
			(net "GND")
		)
	)
	(footprint ""
		(layer "F.Cu")
		(at 99.614736 -127.787654 -90)
		(property "Reference" "R1458"
			(at 0 0 270)
			(layer "F.SilkS")
			(hide yes)
			(effects
				(font
					(size 1.27 1.27)
				)
			)
		)
		(property "Value" ""
			(at 0 0 270)
			(layer "F.Fab")
			(effects
				(font
					(size 1.27 1.27)
				)
			)
		)
		(duplicate_pad_numbers_are_jumpers no)
		(fp_line
			(start -0.7874 0.4064)
			(end -0.7874 -0.4064)
			(stroke
				(width 0.1524)
				(type default)
			)
			(layer "F.SilkS")
		)
		(fp_line
			(start 0.7874 0.4064)
			(end -0.7874 0.4064)
			(stroke
				(width 0.1524)
				(type default)
			)
			(layer "F.SilkS")
		)
		(fp_line
			(start -0.7874 -0.4064)
			(end 0.7874 -0.4064)
			(stroke
				(width 0.1524)
				(type default)
			)
			(layer "F.SilkS")
		)
		(fp_line
			(start 0.7874 -0.4064)
			(end 0.7874 0.4064)
			(stroke
				(width 0.1524)
				(type default)
			)
			(layer "F.SilkS")
		)
		(fp_line
			(start -0.67945 0.3048)
			(end -0.67945 -0.305054)
			(stroke
				(width 0.1)
				(type default)
			)
			(layer "F.Fab")
		)
		(fp_line
			(start -0.12065 0.3048)
			(end -0.67945 0.3048)
			(stroke
				(width 0.1)
				(type default)
			)
			(layer "F.Fab")
		)
		(fp_line
			(start 0.120396 0.3048)
			(end 0.120396 0.2794)
			(stroke
				(width 0.1)
				(type default)
			)
			(layer "F.Fab")
		)
		(fp_line
			(start 0.67945 0.3048)
			(end 0.120396 0.3048)
			(stroke
				(width 0.1)
				(type default)
			)
			(layer "F.Fab")
		)
		(fp_line
			(start -0.12065 0.2794)
			(end -0.12065 0.3048)
			(stroke
				(width 0.1)
				(type default)
			)
			(layer "F.Fab")
		)
		(fp_line
			(start 0.120396 0.2794)
			(end -0.12065 0.2794)
			(stroke
				(width 0.1)
				(type default)
			)
			(layer "F.Fab")
		)
		(fp_line
			(start -0.12065 -0.2794)
			(end 0.12065 -0.2794)
			(stroke
				(width 0.1)
				(type default)
			)
			(layer "F.Fab")
		)
		(fp_line
			(start 0.12065 -0.2794)
			(end 0.12065 -0.3048)
			(stroke
				(width 0.1)
				(type default)
			)
			(layer "F.Fab")
		)
		(fp_line
			(start 0.12065 -0.3048)
			(end 0.67945 -0.3048)
			(stroke
				(width 0.1)
				(type default)
			)
			(layer "F.Fab")
		)
		(fp_line
			(start 0.67945 -0.3048)
			(end 0.67945 0.3048)
			(stroke
				(width 0.1)
				(type default)
			)
			(layer "F.Fab")
		)
		(fp_line
			(start -0.67945 -0.305054)
			(end -0.12065 -0.305054)
			(stroke
				(width 0.1)
				(type default)
			)
			(layer "F.Fab")
		)
		(fp_line
			(start -0.12065 -0.305054)
			(end -0.12065 -0.2794)
			(stroke
				(width 0.1)
				(type default)
			)
			(layer "F.Fab")
		)
		(pad "1" smd circle
			(at -0.40005 0 270)
			(size 0 0)
			(layers "F.Cu" "F.Mask" "F.Paste")
			(net "PWRGD_P12V_MEM_CPU0")
		)
		(pad "2" smd circle
			(at 0.40005 0 270)
			(size 0 0)
			(layers "F.Cu" "F.Mask" "F.Paste")
			(net "PWRGD_P12V_MEM_CPU0_R")
		)
	)
	(footprint ""
		(layer "F.Cu")
		(at 293.720012 -34.001964 -90)
		(property "Reference" "BT2"
			(at 5.553964 1.243076 0)
			(unlocked yes)
			(layer "F.SilkS")
			(effects
				(font
					(size 0.7874 0.5842)
					(thickness 0.1524)
				)
				(justify left)
			)
		)
		(property "Value" ""
			(at 0 0 270)
			(layer "F.Fab")
			(effects
				(font
					(size 1.27 1.27)
				)
			)
		)
		(duplicate_pad_numbers_are_jumpers no)
		(fp_line
			(start 3.666236 22.820122)
			(end -3.666236 22.820122)
			(stroke
				(width 0.1524)
				(type default)
			)
			(layer "F.SilkS")
		)
		(fp_line
			(start -4.012692 22.800056)
			(end -3.724148 22.800056)
			(stroke
				(width 0.1524)
				(type default)
			)
			(layer "F.SilkS")
		)
		(fp_line
			(start 3.724148 22.800056)
			(end 4.012692 22.800056)
			(stroke
				(width 0.1524)
				(type default)
			)
			(layer "F.SilkS")
		)
		(fp_line
			(start -3.800094 1.807464)
			(end -3.800094 -1.180084)
			(stroke
				(width 0.1524)
				(type default)
			)
			(layer "F.SilkS")
		)
		(fp_line
			(start 3.899916 1.737614)
			(end 3.899916 -1.260094)
			(stroke
				(width 0.1524)
				(type default)
			)
			(layer "F.SilkS")
		)
		(fp_line
			(start -3.800094 -1.180084)
			(end 3.800094 -1.180084)
			(stroke
				(width 0.1524)
				(type default)
			)
			(layer "F.SilkS")
		)
		(fp_line
			(start 3.800094 -1.180084)
			(end 3.800094 1.807464)
			(stroke
				(width 0.1524)
				(type default)
			)
			(layer "F.SilkS")
		)
		(fp_line
			(start -3.899916 -1.260094)
			(end -3.899916 1.737614)
			(stroke
				(width 0.1524)
				(type default)
			)
			(layer "F.SilkS")
		)
		(fp_line
			(start 3.899916 -1.260094)
			(end -3.899916 -1.260094)
			(stroke
				(width 0.1524)
				(type default)
			)
			(layer "F.SilkS")
		)
		(fp_arc
			(start -3.666236 22.820122)
			(mid -11.149833 12.361061)
			(end -3.800094 1.807464)
			(stroke
				(width 0.1524)
				(type default)
			)
			(layer "F.SilkS")
		)
		(fp_arc
			(start -4.012692 22.800056)
			(mid -11.249872 12.229778)
			(end -3.899916 1.737614)
			(stroke
				(width 0.1524)
				(type default)
			)
			(layer "F.SilkS")
		)
		(fp_arc
			(start 3.800094 1.807464)
			(mid 11.149895 12.361062)
			(end 3.666236 22.820122)
			(stroke
				(width 0.1524)
				(type default)
			)
			(layer "F.SilkS")
		)
		(fp_arc
			(start 3.899916 1.737614)
			(mid 11.249813 12.229779)
			(end 4.012692 22.800056)
			(stroke
				(width 0.1524)
				(type default)
			)
			(layer "F.SilkS")
		)
		(fp_line
			(start 3.666236 22.820122)
			(end -3.666236 22.820122)
			(stroke
				(width 0.1)
				(type default)
			)
			(layer "F.Fab")
		)
		(fp_line
			(start -3.800094 1.807464)
			(end -3.800094 -1.180084)
			(stroke
				(width 0.1)
				(type default)
			)
			(layer "F.Fab")
		)
		(fp_line
			(start -3.800094 -1.180084)
			(end 3.800094 -1.180084)
			(stroke
				(width 0.1)
				(type default)
			)
			(layer "F.Fab")
		)
		(fp_line
			(start 3.800094 -1.180084)
			(end 3.800094 1.807464)
			(stroke
				(width 0.1)
				(type default)
			)
			(layer "F.Fab")
		)
		(fp_arc
			(start -3.666236 22.820122)
			(mid -11.149833 12.361061)
			(end -3.800094 1.807464)
			(stroke
				(width 0.1)
				(type default)
			)
			(layer "F.Fab")
		)
		(fp_arc
			(start 3.800094 1.807464)
			(mid 11.149895 12.361062)
			(end 3.666236 22.820122)
			(stroke
				(width 0.1)
				(type default)
			)
			(layer "F.Fab")
		)
		(fp_text user "-"
			(at 0.26035 22.7076 180)
			(unlocked yes)
			(layer "F.Fab")
			(effects
				(font
					(size 1.905 1.4224)
					(thickness 0.1524)
				)
				(justify left)
			)
		)
		(fp_text user "+"
			(at 0.20955 -2.5908 180)
			(unlocked yes)
			(layer "F.Fab")
			(effects
				(font
					(size 1.905 1.4224)
					(thickness 0.1524)
				)
				(justify left)
			)
		)
		(pad "1" thru_hole rect
			(at 0 0 270)
			(size 1.6256 1.6256)
			(drill 1.1176)
			(layers "*.Cu" "*.Mask")
			(remove_unused_layers no)
			(net "P3V_BAT")
			(clearance 0)
			(padstack
				(mode front_inner_back)
				(layer "Inner"
					(shape circle)
					(size 1.6256 1.6256)
					(clearance 0)
				)
				(layer "B.Cu"
					(shape rect)
					(size 1.6256 1.6256)
					(clearance 0)
				)
			)
		)
		(pad "2" thru_hole circle
			(at 0 19.99996 270)
			(size 1.524 1.524)
			(drill 1.016)
			(layers "*.Cu" "*.Mask")
			(remove_unused_layers no)
			(net "GND")
			(clearance 0)
		)
	)
	(footprint ""
		(layer "F.Cu")
		(at 430.022 -58.42 -90)
		(property "Reference" "R8017"
			(at 0 0 270)
			(layer "F.SilkS")
			(hide yes)
			(effects
				(font
					(size 1.27 1.27)
				)
			)
		)
		(property "Value" ""
			(at 0 0 270)
			(layer "F.Fab")
			(effects
				(font
					(size 1.27 1.27)
				)
			)
		)
		(duplicate_pad_numbers_are_jumpers no)
		(fp_line
			(start -0.7874 0.4064)
			(end -0.7874 -0.4064)
			(stroke
				(width 0.1524)
				(type default)
			)
			(layer "F.SilkS")
		)
		(fp_line
			(start 0.7874 0.4064)
			(end -0.7874 0.4064)
			(stroke
				(width 0.1524)
				(type default)
			)
			(layer "F.SilkS")
		)
		(fp_line
			(start -0.7874 -0.4064)
			(end 0.7874 -0.4064)
			(stroke
				(width 0.1524)
				(type default)
			)
			(layer "F.SilkS")
		)
		(fp_line
			(start 0.7874 -0.4064)
			(end 0.7874 0.4064)
			(stroke
				(width 0.1524)
				(type default)
			)
			(layer "F.SilkS")
		)
		(fp_line
			(start -0.67945 0.3048)
			(end -0.67945 -0.305054)
			(stroke
				(width 0.1)
				(type default)
			)
			(layer "F.Fab")
		)
		(fp_line
			(start -0.12065 0.3048)
			(end -0.67945 0.3048)
			(stroke
				(width 0.1)
				(type default)
			)
			(layer "F.Fab")
		)
		(fp_line
			(start 0.120396 0.3048)
			(end 0.120396 0.2794)
			(stroke
				(width 0.1)
				(type default)
			)
			(layer "F.Fab")
		)
		(fp_line
			(start 0.67945 0.3048)
			(end 0.120396 0.3048)
			(stroke
				(width 0.1)
				(type default)
			)
			(layer "F.Fab")
		)
		(fp_line
			(start -0.12065 0.2794)
			(end -0.12065 0.3048)
			(stroke
				(width 0.1)
				(type default)
			)
			(layer "F.Fab")
		)
		(fp_line
			(start 0.120396 0.2794)
			(end -0.12065 0.2794)
			(stroke
				(width 0.1)
				(type default)
			)
			(layer "F.Fab")
		)
		(fp_line
			(start -0.12065 -0.2794)
			(end 0.12065 -0.2794)
			(stroke
				(width 0.1)
				(type default)
			)
			(layer "F.Fab")
		)
		(fp_line
			(start 0.12065 -0.2794)
			(end 0.12065 -0.3048)
			(stroke
				(width 0.1)
				(type default)
			)
			(layer "F.Fab")
		)
		(fp_line
			(start 0.12065 -0.3048)
			(end 0.67945 -0.3048)
			(stroke
				(width 0.1)
				(type default)
			)
			(layer "F.Fab")
		)
		(fp_line
			(start 0.67945 -0.3048)
			(end 0.67945 0.3048)
			(stroke
				(width 0.1)
				(type default)
			)
			(layer "F.Fab")
		)
		(fp_line
			(start -0.67945 -0.305054)
			(end -0.12065 -0.305054)
			(stroke
				(width 0.1)
				(type default)
			)
			(layer "F.Fab")
		)
		(fp_line
			(start -0.12065 -0.305054)
			(end -0.12065 -0.2794)
			(stroke
				(width 0.1)
				(type default)
			)
			(layer "F.Fab")
		)
		(pad "1" smd circle
			(at -0.40005 0 270)
			(size 0 0)
			(layers "F.Cu" "F.Mask" "F.Paste")
			(net "P3V3_AUX")
		)
		(pad "2" smd circle
			(at 0.40005 0 270)
			(size 0 0)
			(layers "F.Cu" "F.Mask" "F.Paste")
			(net "U124_VCC")
		)
	)
	(footprint ""
		(layer "F.Cu")
		(at 134.474712 -400.76882 180)
		(property "Reference" "C7005"
			(at -1.133856 -2.910332 0)
			(unlocked yes)
			(layer "F.SilkS")
			(effects
				(font
					(size 0.7874 0.5842)
					(thickness 0.1524)
				)
				(justify left)
			)
		)
		(property "Value" ""
			(at 0 0 180)
			(layer "F.Fab")
			(effects
				(font
					(size 1.27 1.27)
				)
			)
		)
		(duplicate_pad_numbers_are_jumpers no)
		(fp_line
			(start 4.53898 2.15011)
			(end -4.53898 2.15011)
			(stroke
				(width 0.1524)
				(type default)
			)
			(layer "F.SilkS")
		)
		(fp_line
			(start 4.53898 -2.15011)
			(end 4.53898 2.15011)
			(stroke
				(width 0.1524)
				(type default)
			)
			(layer "F.SilkS")
		)
		(fp_line
			(start -4.53898 2.15011)
			(end -4.53898 -2.15011)
			(stroke
				(width 0.1524)
				(type default)
			)
			(layer "F.SilkS")
		)
		(fp_line
			(start -4.53898 -2.15011)
			(end 4.53898 -2.15011)
			(stroke
				(width 0.1524)
				(type default)
			)
			(layer "F.SilkS")
		)
		(fp_line
			(start -4.53898 -2.150618)
			(end -4.539742 2.152142)
			(stroke
				(width 0.1524)
				(type default)
			)
			(layer "F.SilkS")
		)
		(fp_line
			(start -4.69138 -2.150618)
			(end -4.692396 2.161032)
			(stroke
				(width 0.1524)
				(type default)
			)
			(layer "F.SilkS")
		)
		(fp_line
			(start -4.83108 2.150364)
			(end -4.447794 2.149348)
			(stroke
				(width 0.1524)
				(type default)
			)
			(layer "F.SilkS")
		)
		(fp_line
			(start -4.84378 -2.150618)
			(end -4.53898 -2.150618)
			(stroke
				(width 0.1524)
				(type default)
			)
			(layer "F.SilkS")
		)
		(fp_line
			(start -4.84378 -2.150618)
			(end -4.842256 2.163064)
			(stroke
				(width 0.1524)
				(type default)
			)
			(layer "F.SilkS")
		)
		(fp_line
			(start 3.64998 2.15011)
			(end -3.64998 2.15011)
			(stroke
				(width 0.1)
				(type default)
			)
			(layer "F.Fab")
		)
		(fp_line
			(start 3.64998 -2.15011)
			(end 3.64998 2.15011)
			(stroke
				(width 0.1)
				(type default)
			)
			(layer "F.Fab")
		)
		(fp_line
			(start -3.64998 2.15011)
			(end -3.64998 -2.15011)
			(stroke
				(width 0.1)
				(type default)
			)
			(layer "F.Fab")
		)
		(fp_line
			(start -3.64998 -2.15011)
			(end 3.64998 -2.15011)
			(stroke
				(width 0.1)
				(type default)
			)
			(layer "F.Fab")
		)
		(fp_text user "-"
			(at 4.869434 -0.582168 180)
			(unlocked yes)
			(layer "F.SilkS")
			(effects
				(font
					(size 1.905 1.4224)
					(thickness 0.1524)
				)
				(justify left)
			)
		)
		(fp_text user "+"
			(at -6.075172 -1.660398 180)
			(unlocked yes)
			(layer "F.SilkS")
			(effects
				(font
					(size 1.905 1.4224)
					(thickness 0.1524)
				)
				(justify left)
			)
		)
		(fp_text user "-"
			(at 4.313174 -0.094488 180)
			(unlocked yes)
			(layer "F.Fab")
			(effects
				(font
					(size 1.905 1.4224)
					(thickness 0.1524)
				)
				(justify left)
			)
		)
		(fp_text user "+"
			(at -6.214872 -0.337058 180)
			(unlocked yes)
			(layer "F.Fab")
			(effects
				(font
					(size 1.905 1.4224)
					(thickness 0.1524)
				)
				(justify left)
			)
		)
		(pad "1" smd rect
			(at -3.199892 0 180)
			(size 2.413 2.8194)
			(layers "F.Cu" "F.Mask" "F.Paste")
			(net "P0V9_CPU1_RT_2D")
		)
		(pad "2" smd rect
			(at 3.199892 0 180)
			(size 2.413 2.8194)
			(layers "F.Cu" "F.Mask" "F.Paste")
			(net "GND")
		)
	)
)
